# S9S_MB_2U (Grand Teton) — schematic netlist excerpt (pin names and nets, part order shuffled) for the footprints in the layout excerpt that follows; sources: Cadence DE-HDL packaged netlist, KiCad conversion of 03242023_DA0F0TMBIJ0_F0T_Motherboard_J_brd_V01_OCP.brd

PC556  Q_CAP  2.2UF 10V 10% X6S  pkg C0402  page 285 : A = PVCCIN_CPU1_VDD2 ; B = GND
R4728  Q_RES  0 5% CHIP  pkg 0402LF  page 227 : A = PRSNT_SWB_ISO_N ; B = PRSNT_SWB_ISO_R1_N

(kicad_pcb
	(version 20260206)
	(generator "pcbnew")
	(generator_version "10.0")
	(general
		(thickness 1.6)
		(legacy_teardrops no)
	)
	(paper "A4")
	(title_block
		(title "03242023_DA0F0TMBIJ0_F0T_Motherboard_J_brd_V01_OCP.brd")
		(comment 1 "Grand Teton / footprints 3208-3209 of 6105")
	)
	(layers
		(0 "F.Cu" signal "TOP")
		(4 "In1.Cu" signal "GND")
		(6 "In2.Cu" signal "IN1")
		(8 "In3.Cu" signal "GND1")
		(10 "In4.Cu" signal "IN2")
		(12 "In5.Cu" signal "GND2")
		(14 "In6.Cu" signal "IN3")
		(16 "In7.Cu" signal "GND3")
		(18 "In8.Cu" signal "VCC")
		(20 "In9.Cu" signal "VCC1")
		(22 "In10.Cu" signal "GND4")
		(24 "In11.Cu" signal "IN4")
		(26 "In12.Cu" signal "GND5")
		(28 "In13.Cu" signal "IN5")
		(30 "In14.Cu" signal "GND6")
		(32 "In15.Cu" signal "IN6")
		(34 "In16.Cu" signal "GND7")
		(2 "B.Cu" signal "BOTTOM")
		(9 "F.Adhes" user "F.Adhesive")
		(11 "B.Adhes" user "B.Adhesive")
		(13 "F.Paste" user "Package Geometry/Pastemask Top")
		(15 "B.Paste" user "Package Geometry/Pastemask Bottom")
		(5 "F.SilkS" user "Ref Des/Silkscreen Top")
		(7 "B.SilkS" user "Ref Des/Silkscreen Bottom")
		(1 "F.Mask" user "Board Geometry/Soldermask Top")
		(3 "B.Mask" user "Board Geometry/Soldermask Bottom")
		(17 "Dwgs.User" user "User.Drawings")
		(19 "Cmts.User" user "User.Comments")
		(21 "Eco1.User" user "User.Eco1")
		(23 "Eco2.User" user "User.Eco2")
		(25 "Edge.Cuts" user "Board Geometry/Outline")
		(27 "Margin" user)
		(31 "F.CrtYd" user "Package Geometry/Place Bound Top")
		(29 "B.CrtYd" user "Package Geometry/Place Bound Bottom")
		(35 "F.Fab" user "Ref Des/Assembly Top")
		(33 "B.Fab" user "Ref Des/Assembly Bottom")
	)
	(footprint ""
		(layer "F.Cu")
		(at 101.58349 -336.192368 90)
		(property "Reference" "PC556"
			(at 0 0 90)
			(layer "F.SilkS")
			(hide yes)
			(effects
				(font
					(size 1.27 1.27)
				)
			)
		)
		(property "Value" ""
			(at 0 0 90)
			(layer "F.Fab")
			(effects
				(font
					(size 1.27 1.27)
				)
			)
		)
		(duplicate_pad_numbers_are_jumpers no)
		(fp_line
			(start 0.7874 -0.4064)
			(end 0.7874 0.4064)
			(stroke
				(width 0.1524)
				(type default)
			)
			(layer "F.SilkS")
		)
		(fp_line
			(start -0.7874 -0.4064)
			(end 0.7874 -0.4064)
			(stroke
				(width 0.1524)
				(type default)
			)
			(layer "F.SilkS")
		)
		(fp_line
			(start 0.7874 0.4064)
			(end -0.7874 0.4064)
			(stroke
				(width 0.1524)
				(type default)
			)
			(layer "F.SilkS")
		)
		(fp_line
			(start -0.7874 0.4064)
			(end -0.7874 -0.4064)
			(stroke
				(width 0.1524)
				(type default)
			)
			(layer "F.SilkS")
		)
		(fp_line
			(start -0.12065 -0.305054)
			(end -0.12065 -0.2794)
			(stroke
				(width 0.1)
				(type default)
			)
			(layer "F.Fab")
		)
		(fp_line
			(start -0.67945 -0.305054)
			(end -0.12065 -0.305054)
			(stroke
				(width 0.1)
				(type default)
			)
			(layer "F.Fab")
		)
		(fp_line
			(start 0.67945 -0.3048)
			(end 0.67945 0.3048)
			(stroke
				(width 0.1)
				(type default)
			)
			(layer "F.Fab")
		)
		(fp_line
			(start 0.12065 -0.3048)
			(end 0.67945 -0.3048)
			(stroke
				(width 0.1)
				(type default)
			)
			(layer "F.Fab")
		)
		(fp_line
			(start 0.12065 -0.2794)
			(end 0.12065 -0.3048)
			(stroke
				(width 0.1)
				(type default)
			)
			(layer "F.Fab")
		)
		(fp_line
			(start -0.12065 -0.2794)
			(end 0.12065 -0.2794)
			(stroke
				(width 0.1)
				(type default)
			)
			(layer "F.Fab")
		)
		(fp_line
			(start 0.120396 0.2794)
			(end -0.12065 0.2794)
			(stroke
				(width 0.1)
				(type default)
			)
			(layer "F.Fab")
		)
		(fp_line
			(start -0.12065 0.2794)
			(end -0.12065 0.3048)
			(stroke
				(width 0.1)
				(type default)
			)
			(layer "F.Fab")
		)
		(fp_line
			(start 0.67945 0.3048)
			(end 0.120396 0.3048)
			(stroke
				(width 0.1)
				(type default)
			)
			(layer "F.Fab")
		)
		(fp_line
			(start 0.120396 0.3048)
			(end 0.120396 0.2794)
			(stroke
				(width 0.1)
				(type default)
			)
			(layer "F.Fab")
		)
		(fp_line
			(start -0.12065 0.3048)
			(end -0.67945 0.3048)
			(stroke
				(width 0.1)
				(type default)
			)
			(layer "F.Fab")
		)
		(fp_line
			(start -0.67945 0.3048)
			(end -0.67945 -0.305054)
			(stroke
				(width 0.1)
				(type default)
			)
			(layer "F.Fab")
		)
		(pad "1" smd circle
			(at -0.40005 0 90)
			(size 0 0)
			(layers "F.Cu" "F.Mask" "F.Paste")
			(net "PVCCIN_CPU1_VDD2")
		)
		(pad "2" smd circle
			(at 0.40005 0 90)
			(size 0 0)
			(layers "F.Cu" "F.Mask" "F.Paste")
			(net "GND")
		)
	)
	(footprint ""
		(layer "F.Cu")
		(at 18.8214 -410.7942 90)
		(property "Reference" "R4728"
			(at 0 0 90)
			(layer "F.SilkS")
			(hide yes)
			(effects
				(font
					(size 1.27 1.27)
				)
			)
		)
		(property "Value" ""
			(at 0 0 90)
			(layer "F.Fab")
			(effects
				(font
					(size 1.27 1.27)
				)
			)
		)
		(duplicate_pad_numbers_are_jumpers no)
		(fp_line
			(start 0.7874 -0.406146)
			(end 0.7874 0.406146)
			(stroke
				(width 0.1524)
				(type default)
			)
			(layer "F.SilkS")
		)
		(fp_line
			(start -0.7874 -0.406146)
			(end 0.7874 -0.406146)
			(stroke
				(width 0.1524)
				(type default)
			)
			(layer "F.SilkS")
		)
		(fp_line
			(start 0.7874 0.406146)
			(end -0.7874 0.406146)
			(stroke
				(width 0.1524)
				(type default)
			)
			(layer "F.SilkS")
		)
		(fp_line
			(start -0.7874 0.406146)
			(end -0.7874 -0.406146)
			(stroke
				(width 0.1524)
				(type default)
			)
			(layer "F.SilkS")
		)
		(fp_line
			(start -0.12065 -0.305054)
			(end -0.12065 -0.2794)
			(stroke
				(width 0.1)
				(type default)
			)
			(layer "F.Fab")
		)
		(fp_line
			(start -0.67945 -0.305054)
			(end -0.12065 -0.305054)
			(stroke
				(width 0.1)
				(type default)
			)
			(layer "F.Fab")
		)
		(fp_line
			(start 0.67945 -0.3048)
			(end 0.67945 0.3048)
			(stroke
				(width 0.1)
				(type default)
			)
			(layer "F.Fab")
		)
		(fp_line
			(start 0.120396 -0.3048)
			(end 0.67945 -0.3048)
			(stroke
				(width 0.1)
				(type default)
			)
			(layer "F.Fab")
		)
		(fp_line
			(start 0.12065 -0.2794)
			(end 0.120396 -0.3048)
			(stroke
				(width 0.1)
				(type default)
			)
			(layer "F.Fab")
		)
		(fp_line
			(start -0.12065 -0.2794)
			(end 0.12065 -0.2794)
			(stroke
				(width 0.1)
				(type default)
			)
			(layer "F.Fab")
		)
		(fp_line
			(start 0.120396 0.2794)
			(end -0.12065 0.2794)
			(stroke
				(width 0.1)
				(type default)
			)
			(layer "F.Fab")
		)
		(fp_line
			(start -0.12065 0.2794)
			(end -0.120396 0.3048)
			(stroke
				(width 0.1)
				(type default)
			)
			(layer "F.Fab")
		)
		(fp_line
			(start 0.67945 0.3048)
			(end 0.120396 0.3048)
			(stroke
				(width 0.1)
				(type default)
			)
			(layer "F.Fab")
		)
		(fp_line
			(start 0.120396 0.3048)
			(end 0.120396 0.2794)
			(stroke
				(width 0.1)
				(type default)
			)
			(layer "F.Fab")
		)
		(fp_line
			(start -0.120396 0.3048)
			(end -0.67945 0.3048)
			(stroke
				(width 0.1)
				(type default)
			)
			(layer "F.Fab")
		)
		(fp_line
			(start -0.67945 0.3048)
			(end -0.67945 -0.305054)
			(stroke
				(width 0.1)
				(type default)
			)
			(layer "F.Fab")
		)
		(pad "1" smd circle
			(at -0.40005 0 90)
			(size 0 0)
			(layers "F.Cu" "F.Mask" "F.Paste")
			(net "PRSNT_SWB_ISO_N")
		)
		(pad "2" smd circle
			(at 0.40005 0 90)
			(size 0 0)
			(layers "F.Cu" "F.Mask" "F.Paste")
			(net "PRSNT_SWB_ISO_R1_N")
		)
	)
)
